# S9S_MB_2U (Grand Teton) — schematic netlist excerpt (pin names and nets, part order shuffled) for the footprints in the layout excerpt that follows; sources: Cadence DE-HDL packaged netlist, KiCad conversion of 03242023_DA0F0TMBIJ0_F0T_Motherboard_J_brd_V01_OCP.brd

X25  TP_TDR_4P_FTS  TP_TDR_4P_DIP EMPTY  pkg TH  page 309
  S1  = TDR_DIFF_85_IN5_DP
  P1  = T1_GND
  P2  = T1_GND
  S2  = TDR_DIFF_85_IN5_DN

PC285_P0_3  Q_CAP  22UF 16V 20% X6S  pkg C0805  page 268 : A = SW_P12V_PVCCIN_CPU0_FLT ; B = GND
C2292  Q_CAP  0.1UF 6.3V 10% X6S  pkg C0201  page 169 : A = USB3_PCH_RX_BUF_C_DN<4> ; B = USB3_PCH_RX_BUF_DN<4>

(kicad_pcb
	(version 20260206)
	(generator "pcbnew")
	(generator_version "10.0")
	(general
		(thickness 1.6)
		(legacy_teardrops no)
	)
	(paper "A4")
	(title_block
		(title "03242023_DA0F0TMBIJ0_F0T_Motherboard_J_brd_V01_OCP.brd")
		(comment 1 "Grand Teton / footprints 5254-5256 of 6105")
	)
	(layers
		(0 "F.Cu" signal "TOP")
		(4 "In1.Cu" signal "GND")
		(6 "In2.Cu" signal "IN1")
		(8 "In3.Cu" signal "GND1")
		(10 "In4.Cu" signal "IN2")
		(12 "In5.Cu" signal "GND2")
		(14 "In6.Cu" signal "IN3")
		(16 "In7.Cu" signal "GND3")
		(18 "In8.Cu" signal "VCC")
		(20 "In9.Cu" signal "VCC1")
		(22 "In10.Cu" signal "GND4")
		(24 "In11.Cu" signal "IN4")
		(26 "In12.Cu" signal "GND5")
		(28 "In13.Cu" signal "IN5")
		(30 "In14.Cu" signal "GND6")
		(32 "In15.Cu" signal "IN6")
		(34 "In16.Cu" signal "GND7")
		(2 "B.Cu" signal "BOTTOM")
		(9 "F.Adhes" user "F.Adhesive")
		(11 "B.Adhes" user "B.Adhesive")
		(13 "F.Paste" user "Package Geometry/Pastemask Top")
		(15 "B.Paste" user "Package Geometry/Pastemask Bottom")
		(5 "F.SilkS" user "Ref Des/Silkscreen Top")
		(7 "B.SilkS" user "Ref Des/Silkscreen Bottom")
		(1 "F.Mask" user "Board Geometry/Soldermask Top")
		(3 "B.Mask" user "Board Geometry/Soldermask Bottom")
		(17 "Dwgs.User" user "User.Drawings")
		(19 "Cmts.User" user "User.Comments")
		(21 "Eco1.User" user "User.Eco1")
		(23 "Eco2.User" user "User.Eco2")
		(25 "Edge.Cuts" user "Board Geometry/Outline")
		(27 "Margin" user)
		(31 "F.CrtYd" user "Package Geometry/Place Bound Top")
		(29 "B.CrtYd" user "Package Geometry/Place Bound Bottom")
		(35 "F.Fab" user "Ref Des/Assembly Top")
		(33 "B.Fab" user "Ref Des/Assembly Bottom")
	)
	(footprint ""
		(layer "B.Cu")
		(at 362.762038 -337.564984 -90)
		(property "Reference" "PC285_P0_3"
			(at 0 0 90)
			(layer "B.SilkS")
			(hide yes)
			(effects
				(font
					(size 1.27 1.27)
				)
				(justify mirror)
			)
		)
		(property "Value" ""
			(at 0 0 90)
			(layer "B.Fab")
			(effects
				(font
					(size 1.27 1.27)
				)
				(justify mirror)
			)
		)
		(duplicate_pad_numbers_are_jumpers no)
		(fp_line
			(start -1.524 0.762)
			(end 1.524 0.762)
			(stroke
				(width 0.1524)
				(type default)
			)
			(layer "B.SilkS")
		)
		(fp_line
			(start 1.524 0.762)
			(end 1.524 -0.762)
			(stroke
				(width 0.1524)
				(type default)
			)
			(layer "B.SilkS")
		)
		(fp_line
			(start -1.524 -0.762)
			(end -1.524 0.762)
			(stroke
				(width 0.1524)
				(type default)
			)
			(layer "B.SilkS")
		)
		(fp_line
			(start 1.524 -0.762)
			(end -1.524 -0.762)
			(stroke
				(width 0.1524)
				(type default)
			)
			(layer "B.SilkS")
		)
		(fp_line
			(start -1.1049 0.724916)
			(end -1.1049 -0.724916)
			(stroke
				(width 0.1)
				(type default)
			)
			(layer "B.Fab")
		)
		(fp_line
			(start 1.1049 0.724916)
			(end -1.1049 0.724916)
			(stroke
				(width 0.1)
				(type default)
			)
			(layer "B.Fab")
		)
		(fp_line
			(start -1.1049 -0.724916)
			(end 1.1049 -0.724916)
			(stroke
				(width 0.1)
				(type default)
			)
			(layer "B.Fab")
		)
		(fp_line
			(start 1.1049 -0.724916)
			(end 1.1049 0.724916)
			(stroke
				(width 0.1)
				(type default)
			)
			(layer "B.Fab")
		)
		(pad "1" smd rect
			(at 0.889 0 270)
			(size 1.016 1.27)
			(layers "B.Cu" "B.Mask" "B.Paste")
			(net "SW_P12V_PVCCIN_CPU0_FLT")
		)
		(pad "2" smd rect
			(at -0.889 0 270)
			(size 1.016 1.27)
			(layers "B.Cu" "B.Mask" "B.Paste")
			(net "GND")
		)
	)
	(footprint ""
		(layer "B.Cu")
		(at 509.384808 -153.16708 90)
		(property "Reference" "X25"
			(at 1.517142 2.940558 270)
			(unlocked yes)
			(layer "B.SilkS")
			(effects
				(font
					(size 0.7874 0.5842)
					(thickness 0.1524)
				)
				(justify left mirror)
			)
		)
		(property "Value" ""
			(at 0 0 90)
			(layer "B.Fab")
			(effects
				(font
					(size 1.27 1.27)
				)
				(justify mirror)
			)
		)
		(property "Device Type" "TP_TDR_4P_FTS_TH-TP_TDR_4P_DIPA"
			(at -1.30175 1.27 0)
			(unlocked yes)
			(layer "B.Fab")
			(hide yes)
			(effects
				(font
					(size 0.635 0.4064)
					(thickness 0.1524)
				)
				(justify mirror)
			)
		)
		(property "User Part Number" "N_A"
			(at -1.30175 1.27 0)
			(unlocked yes)
			(layer "Cmts.User")
			(hide yes)
			(effects
				(font
					(size 0.635 0.4064)
					(thickness 0.1524)
				)
				(justify mirror)
			)
		)
		(duplicate_pad_numbers_are_jumpers no)
		(fp_line
			(start 0 -1.27)
			(end 0 -0.635)
			(stroke
				(width 0.1524)
				(type default)
			)
			(layer "B.SilkS")
		)
		(fp_line
			(start -2.54 -1.27)
			(end 0 -1.27)
			(stroke
				(width 0.1524)
				(type default)
			)
			(layer "B.SilkS")
		)
		(fp_line
			(start -2.54 -1.1303)
			(end -2.54 -1.27)
			(stroke
				(width 0.1524)
				(type default)
			)
			(layer "B.SilkS")
		)
		(fp_line
			(start 0 0.635)
			(end 0 1.905)
			(stroke
				(width 0.1524)
				(type default)
			)
			(layer "B.SilkS")
		)
		(fp_line
			(start -2.54 1.4097)
			(end -2.54 1.1303)
			(stroke
				(width 0.1524)
				(type default)
			)
			(layer "B.SilkS")
		)
		(fp_line
			(start 0 3.175)
			(end 0 3.81)
			(stroke
				(width 0.1524)
				(type default)
			)
			(layer "B.SilkS")
		)
		(fp_line
			(start 0 3.81)
			(end -2.54 3.81)
			(stroke
				(width 0.1524)
				(type default)
			)
			(layer "B.SilkS")
		)
		(fp_line
			(start -2.54 3.81)
			(end -2.54 3.6703)
			(stroke
				(width 0.1524)
				(type default)
			)
			(layer "B.SilkS")
		)
		(fp_poly
			(pts
				(xy 2.917444 -0.951484) (xy 2.917444 0.572516) (xy 1.393444 -0.189484)
			)
			(stroke
				(width 0)
				(type default)
			)
			(fill yes)
			(layer "B.SilkS")
		)
		(fp_line
			(start 0 -1.27)
			(end 0 3.81)
			(stroke
				(width 0.1)
				(type default)
			)
			(layer "B.Fab")
		)
		(fp_line
			(start -2.54 -1.27)
			(end 0 -1.27)
			(stroke
				(width 0.1)
				(type default)
			)
			(layer "B.Fab")
		)
		(fp_line
			(start 0 3.81)
			(end -2.54 3.81)
			(stroke
				(width 0.1)
				(type default)
			)
			(layer "B.Fab")
		)
		(fp_line
			(start -2.54 3.81)
			(end -2.54 -1.27)
			(stroke
				(width 0.1)
				(type default)
			)
			(layer "B.Fab")
		)
		(fp_poly
			(pts
				(xy 0.761746 0) (xy 2.285746 -0.762) (xy 2.285746 0.762)
			)
			(stroke
				(width 0)
				(type default)
			)
			(fill yes)
			(layer "B.Fab")
		)
		(pad "1" thru_hole circle
			(at 0 0 270)
			(size 1.0033 1.0033)
			(drill 0.249936)
			(layers "*.Cu" "*.Mask")
			(remove_unused_layers no)
			(net "TDR_DIFF_85_IN5_DP")
			(clearance 0.10795)
			(padstack
				(mode front_inner_back)
				(layer "Inner"
					(shape circle)
					(size 0.8001 0.8001)
					(clearance 0.1524)
				)
				(layer "B.Cu"
					(shape circle)
					(size 1.0033 1.0033)
					(thermal_gap 0.10795)
					(clearance 0.10795)
				)
			)
		)
		(pad "2" thru_hole circle
			(at -2.54 0 270)
			(size 1.9939 1.9939)
			(drill 0.249936)
			(layers "*.Cu" "*.Mask")
			(remove_unused_layers no)
			(net "T1_GND")
			(clearance 0.10795)
			(padstack
				(mode front_inner_back)
				(layer "Inner"
					(shape circle)
					(size 0.8001 0.8001)
					(clearance 0.1524)
				)
				(layer "B.Cu"
					(shape circle)
					(size 1.9939 1.9939)
					(thermal_gap 0.10795)
					(clearance 0.10795)
				)
			)
		)
		(pad "3" thru_hole circle
			(at -2.54 2.54 270)
			(size 1.9939 1.9939)
			(drill 0.249936)
			(layers "*.Cu" "*.Mask")
			(remove_unused_layers no)
			(net "T1_GND")
			(clearance 0.10795)
			(padstack
				(mode front_inner_back)
				(layer "Inner"
					(shape circle)
					(size 0.8001 0.8001)
					(clearance 0.1524)
				)
				(layer "B.Cu"
					(shape circle)
					(size 1.9939 1.9939)
					(thermal_gap 0.10795)
					(clearance 0.10795)
				)
			)
		)
		(pad "4" thru_hole circle
			(at 0 2.54 270)
			(size 1.0033 1.0033)
			(drill 0.249936)
			(layers "*.Cu" "*.Mask")
			(remove_unused_layers no)
			(net "TDR_DIFF_85_IN5_DN")
			(clearance 0.10795)
			(padstack
				(mode front_inner_back)
				(layer "Inner"
					(shape circle)
					(size 0.8001 0.8001)
					(clearance 0.1524)
				)
				(layer "B.Cu"
					(shape circle)
					(size 1.0033 1.0033)
					(thermal_gap 0.10795)
					(clearance 0.10795)
				)
			)
		)
	)
	(footprint ""
		(layer "B.Cu")
		(at 123.57862 -27.424888)
		(property "Reference" "C2292"
			(at 0 0 0)
			(layer "B.SilkS")
			(hide yes)
			(effects
				(font
					(size 1.27 1.27)
				)
				(justify mirror)
			)
		)
		(property "Value" ""
			(at 0 0 0)
			(layer "B.Fab")
			(effects
				(font
					(size 1.27 1.27)
				)
				(justify mirror)
			)
		)
		(duplicate_pad_numbers_are_jumpers no)
		(fp_line
			(start -0.299974 -0.150114)
			(end -0.299974 0.150114)
			(stroke
				(width 0.1)
				(type default)
			)
			(layer "B.Fab")
		)
		(fp_line
			(start -0.299974 0.150114)
			(end 0.299974 0.150114)
			(stroke
				(width 0.1)
				(type default)
			)
			(layer "B.Fab")
		)
		(fp_line
			(start 0.299974 -0.150114)
			(end -0.299974 -0.150114)
			(stroke
				(width 0.1)
				(type default)
			)
			(layer "B.Fab")
		)
		(fp_line
			(start 0.299974 0.150114)
			(end 0.299974 -0.150114)
			(stroke
				(width 0.1)
				(type default)
			)
			(layer "B.Fab")
		)
		(pad "1" smd rect
			(at 0.2667 0 180)
			(size 0.3048 0.381)
			(layers "B.Cu" "B.Mask" "B.Paste")
			(net "USB3_PCH_RX_BUF_C_DN<4>")
		)
		(pad "2" smd rect
			(at -0.2667 0 180)
			(size 0.3048 0.381)
			(layers "B.Cu" "B.Mask" "B.Paste")
			(net "USB3_PCH_RX_BUF_DN<4>")
		)
	)
)
